# T6G (Grand Teton) — schematic netlist excerpt (pin names and nets, part order shuffled) for the footprints in the layout excerpt that follows; sources: Cadence DE-HDL packaged netlist, KiCad conversion of 04192023_DAF0TMB3IC0_F0TG_MB_C_brd_V02_OCP.brd

PC13  Q_CAP  0.1UF 25V 10% X7R  pkg 0402  page 193 : A = PVDDCR_CPU0_P0_VCCS ; B = GND
R165  Q_RES  33 5% CHIP  pkg 0402LF  page 80 : A = FM_I3C_CPU0_MUX1_OE_R_N ; B = FM_I3C_CPU0_MUX1_OE_N
C6558  Q_CAP_DIFFBUS  DIFF BUS_0.22UF 6.3V 20% X6S  pkg C0201  page 286 : \1\ = P5E_CPU0_P1_TX_BUF_C_DN<12> ; \2\ = P5E_CPU0_P1_TX_BUF_DN<12>

(kicad_pcb
	(version 20260206)
	(generator "pcbnew")
	(generator_version "10.0")
	(general
		(thickness 1.6)
		(legacy_teardrops no)
	)
	(paper "A4")
	(title_block
		(title "04192023_DAF0TMB3IC0_F0TG_MB_C_brd_V02_OCP.brd")
		(comment 1 "Grand Teton / footprints 7028-7030 of 8354")
	)
	(layers
		(0 "F.Cu" signal "TOP")
		(4 "In1.Cu" signal "GND")
		(6 "In2.Cu" signal "IN1")
		(8 "In3.Cu" signal "GND1")
		(10 "In4.Cu" signal "IN2")
		(12 "In5.Cu" signal "GND2")
		(14 "In6.Cu" signal "IN3")
		(16 "In7.Cu" signal "GND3")
		(18 "In8.Cu" signal "VCC")
		(20 "In9.Cu" signal "VCC1")
		(22 "In10.Cu" signal "GND4")
		(24 "In11.Cu" signal "IN4")
		(26 "In12.Cu" signal "GND5")
		(28 "In13.Cu" signal "IN5")
		(30 "In14.Cu" signal "GND6")
		(32 "In15.Cu" signal "IN6")
		(34 "In16.Cu" signal "GND7")
		(2 "B.Cu" signal "BOTTOM")
		(9 "F.Adhes" user "F.Adhesive")
		(11 "B.Adhes" user "B.Adhesive")
		(13 "F.Paste" user "Package Geometry/Pastemask Top")
		(15 "B.Paste" user "Package Geometry/Pastemask Bottom")
		(5 "F.SilkS" user "Ref Des/Silkscreen Top")
		(7 "B.SilkS" user "Ref Des/Silkscreen Bottom")
		(1 "F.Mask" user "Board Geometry/Soldermask Top")
		(3 "B.Mask" user "Board Geometry/Soldermask Bottom")
		(17 "Dwgs.User" user "User.Drawings")
		(19 "Cmts.User" user "User.Comments")
		(21 "Eco1.User" user "User.Eco1")
		(23 "Eco2.User" user "User.Eco2")
		(25 "Edge.Cuts" user "Board Geometry/Outline")
		(27 "Margin" user)
		(31 "F.CrtYd" user "Package Geometry/Place Bound Top")
		(29 "B.CrtYd" user "Package Geometry/Place Bound Bottom")
		(35 "F.Fab" user "Ref Des/Assembly Top")
		(33 "B.Fab" user "Ref Des/Assembly Bottom")
	)
	(footprint ""
		(layer "B.Cu")
		(at 381.192278 -137.535158 90)
		(property "Reference" "PC13"
			(at 0 0 90)
			(layer "B.SilkS")
			(hide yes)
			(effects
				(font
					(size 1.27 1.27)
				)
				(justify mirror)
			)
		)
		(property "Value" ""
			(at 0 0 90)
			(layer "B.Fab")
			(effects
				(font
					(size 1.27 1.27)
				)
				(justify mirror)
			)
		)
		(duplicate_pad_numbers_are_jumpers no)
		(fp_line
			(start 0.539242 -0.4064)
			(end -0.7874 -0.4064)
			(stroke
				(width 0.1524)
				(type default)
			)
			(layer "B.SilkS")
		)
		(fp_line
			(start -0.7874 -0.4064)
			(end -0.7874 0.4064)
			(stroke
				(width 0.1524)
				(type default)
			)
			(layer "B.SilkS")
		)
		(fp_line
			(start 0.7874 0.4064)
			(end 0.7874 -0.039878)
			(stroke
				(width 0.1524)
				(type default)
			)
			(layer "B.SilkS")
		)
		(fp_line
			(start -0.7874 0.4064)
			(end 0.7874 0.4064)
			(stroke
				(width 0.1524)
				(type default)
			)
			(layer "B.SilkS")
		)
		(fp_line
			(start 0.67945 -0.305054)
			(end 0.12065 -0.305054)
			(stroke
				(width 0.1)
				(type default)
			)
			(layer "B.Fab")
		)
		(fp_line
			(start 0.12065 -0.305054)
			(end 0.12065 -0.2794)
			(stroke
				(width 0.1)
				(type default)
			)
			(layer "B.Fab")
		)
		(fp_line
			(start -0.12065 -0.3048)
			(end -0.67945 -0.3048)
			(stroke
				(width 0.1)
				(type default)
			)
			(layer "B.Fab")
		)
		(fp_line
			(start -0.67945 -0.3048)
			(end -0.67945 0.3048)
			(stroke
				(width 0.1)
				(type default)
			)
			(layer "B.Fab")
		)
		(fp_line
			(start 0.12065 -0.2794)
			(end -0.12065 -0.2794)
			(stroke
				(width 0.1)
				(type default)
			)
			(layer "B.Fab")
		)
		(fp_line
			(start -0.12065 -0.2794)
			(end -0.12065 -0.3048)
			(stroke
				(width 0.1)
				(type default)
			)
			(layer "B.Fab")
		)
		(fp_line
			(start 0.12065 0.2794)
			(end 0.12065 0.3048)
			(stroke
				(width 0.1)
				(type default)
			)
			(layer "B.Fab")
		)
		(fp_line
			(start -0.120396 0.2794)
			(end 0.12065 0.2794)
			(stroke
				(width 0.1)
				(type default)
			)
			(layer "B.Fab")
		)
		(fp_line
			(start 0.67945 0.3048)
			(end 0.67945 -0.305054)
			(stroke
				(width 0.1)
				(type default)
			)
			(layer "B.Fab")
		)
		(fp_line
			(start 0.12065 0.3048)
			(end 0.67945 0.3048)
			(stroke
				(width 0.1)
				(type default)
			)
			(layer "B.Fab")
		)
		(fp_line
			(start -0.120396 0.3048)
			(end -0.120396 0.2794)
			(stroke
				(width 0.1)
				(type default)
			)
			(layer "B.Fab")
		)
		(fp_line
			(start -0.67945 0.3048)
			(end -0.120396 0.3048)
			(stroke
				(width 0.1)
				(type default)
			)
			(layer "B.Fab")
		)
		(pad "1" smd circle
			(at 0.40005 0 270)
			(size 0 0)
			(layers "B.Cu" "B.Mask" "B.Paste")
			(net "PVDDCR_CPU0_P0_VCCS")
		)
		(pad "2" smd circle
			(at -0.40005 0 270)
			(size 0 0)
			(layers "B.Cu" "B.Mask" "B.Paste")
			(net "GND")
		)
	)
	(footprint ""
		(layer "B.Cu")
		(at 342.059006 -416.899344 90)
		(property "Reference" "C6558"
			(at 0 0 90)
			(layer "B.SilkS")
			(hide yes)
			(effects
				(font
					(size 1.27 1.27)
				)
				(justify mirror)
			)
		)
		(property "Value" ""
			(at 0 0 90)
			(layer "B.Fab")
			(effects
				(font
					(size 1.27 1.27)
				)
				(justify mirror)
			)
		)
		(duplicate_pad_numbers_are_jumpers no)
		(fp_line
			(start 0.299974 -0.150114)
			(end -0.299974 -0.150114)
			(stroke
				(width 0.1)
				(type default)
			)
			(layer "B.Fab")
		)
		(fp_line
			(start -0.299974 -0.150114)
			(end -0.299974 0.150114)
			(stroke
				(width 0.1)
				(type default)
			)
			(layer "B.Fab")
		)
		(fp_line
			(start 0.299974 0.150114)
			(end 0.299974 -0.150114)
			(stroke
				(width 0.1)
				(type default)
			)
			(layer "B.Fab")
		)
		(fp_line
			(start -0.299974 0.150114)
			(end 0.299974 0.150114)
			(stroke
				(width 0.1)
				(type default)
			)
			(layer "B.Fab")
		)
		(pad "1" smd rect
			(at 0.2667 0 270)
			(size 0.3048 0.381)
			(layers "B.Cu" "B.Mask" "B.Paste")
			(net "P5E_CPU0_P1_TX_BUF_C_DN<12>")
		)
		(pad "2" smd rect
			(at -0.2667 0 270)
			(size 0.3048 0.381)
			(layers "B.Cu" "B.Mask" "B.Paste")
			(net "P5E_CPU0_P1_TX_BUF_DN<12>")
		)
	)
	(footprint ""
		(layer "B.Cu")
		(at 171.194984 -106.136186)
		(property "Reference" "R165"
			(at 0 0 0)
			(layer "B.SilkS")
			(hide yes)
			(effects
				(font
					(size 1.27 1.27)
				)
				(justify mirror)
			)
		)
		(property "Value" ""
			(at 0 0 0)
			(layer "B.Fab")
			(effects
				(font
					(size 1.27 1.27)
				)
				(justify mirror)
			)
		)
		(duplicate_pad_numbers_are_jumpers no)
		(fp_line
			(start -0.7874 -0.4064)
			(end -0.7874 0.4064)
			(stroke
				(width 0.1524)
				(type default)
			)
			(layer "B.SilkS")
		)
		(fp_line
			(start -0.7874 0.4064)
			(end 0.7874 0.4064)
			(stroke
				(width 0.1524)
				(type default)
			)
			(layer "B.SilkS")
		)
		(fp_line
			(start 0.7874 -0.4064)
			(end -0.7874 -0.4064)
			(stroke
				(width 0.1524)
				(type default)
			)
			(layer "B.SilkS")
		)
		(fp_line
			(start 0.7874 0.4064)
			(end 0.7874 -0.4064)
			(stroke
				(width 0.1524)
				(type default)
			)
			(layer "B.SilkS")
		)
		(fp_line
			(start -0.67945 -0.3048)
			(end -0.67945 0.3048)
			(stroke
				(width 0.1)
				(type default)
			)
			(layer "B.Fab")
		)
		(fp_line
			(start -0.67945 0.3048)
			(end -0.120396 0.3048)
			(stroke
				(width 0.1)
				(type default)
			)
			(layer "B.Fab")
		)
		(fp_line
			(start -0.12065 -0.3048)
			(end -0.67945 -0.3048)
			(stroke
				(width 0.1)
				(type default)
			)
			(layer "B.Fab")
		)
		(fp_line
			(start -0.12065 -0.2794)
			(end -0.12065 -0.3048)
			(stroke
				(width 0.1)
				(type default)
			)
			(layer "B.Fab")
		)
		(fp_line
			(start -0.120396 0.2794)
			(end 0.12065 0.2794)
			(stroke
				(width 0.1)
				(type default)
			)
			(layer "B.Fab")
		)
		(fp_line
			(start -0.120396 0.3048)
			(end -0.120396 0.2794)
			(stroke
				(width 0.1)
				(type default)
			)
			(layer "B.Fab")
		)
		(fp_line
			(start 0.12065 -0.305054)
			(end 0.12065 -0.2794)
			(stroke
				(width 0.1)
				(type default)
			)
			(layer "B.Fab")
		)
		(fp_line
			(start 0.12065 -0.2794)
			(end -0.12065 -0.2794)
			(stroke
				(width 0.1)
				(type default)
			)
			(layer "B.Fab")
		)
		(fp_line
			(start 0.12065 0.2794)
			(end 0.12065 0.3048)
			(stroke
				(width 0.1)
				(type default)
			)
			(layer "B.Fab")
		)
		(fp_line
			(start 0.12065 0.3048)
			(end 0.67945 0.3048)
			(stroke
				(width 0.1)
				(type default)
			)
			(layer "B.Fab")
		)
		(fp_line
			(start 0.67945 -0.305054)
			(end 0.12065 -0.305054)
			(stroke
				(width 0.1)
				(type default)
			)
			(layer "B.Fab")
		)
		(fp_line
			(start 0.67945 0.3048)
			(end 0.67945 -0.305054)
			(stroke
				(width 0.1)
				(type default)
			)
			(layer "B.Fab")
		)
		(pad "1" smd circle
			(at 0.40005 0 180)
			(size 0 0)
			(layers "B.Cu" "B.Mask" "B.Paste")
			(net "FM_I3C_CPU0_MUX1_OE_R_N")
		)
		(pad "2" smd circle
			(at -0.40005 0 180)
			(size 0 0)
			(layers "B.Cu" "B.Mask" "B.Paste")
			(net "FM_I3C_CPU0_MUX1_OE_N")
		)
	)
)
